(kicad_pcb
	(version 20260206)
	(generator "pcbnew")
	(generator_version "10.0")
	(general
		(thickness 1.6)
		(legacy_teardrops no)
	)
	(paper "A4")
	(title_block
		(title "baseboard — 13948-1b.1110WZS1818.brd")
		(comment 1 "Honey Badger (Wiwynn) / footprints 1240-1246 of 2523")
	)
	(layers
		(0 "F.Cu" signal "TOP")
		(4 "In1.Cu" signal "L2GND")
		(6 "In2.Cu" signal "L3")
		(8 "In3.Cu" signal "L4VCC")
		(10 "In4.Cu" signal "L5VCC")
		(12 "In5.Cu" signal "L6")
		(14 "In6.Cu" signal "L7GND")
		(2 "B.Cu" signal "BOTTOM")
		(9 "F.Adhes" user "F.Adhesive")
		(11 "B.Adhes" user "B.Adhesive")
		(13 "F.Paste" user "Package Geometry/Pastemask Top")
		(15 "B.Paste" user "Package Geometry/Pastemask Bottom")
		(5 "F.SilkS" user "Ref Des/Silkscreen Top")
		(7 "B.SilkS" user "Ref Des/Silkscreen Bottom")
		(1 "F.Mask" user "Board Geometry/Soldermask Top")
		(3 "B.Mask" user "Board Geometry/Soldermask Bottom")
		(17 "Dwgs.User" user "User.Drawings")
		(19 "Cmts.User" user "User.Comments")
		(21 "Eco1.User" user "User.Eco1")
		(23 "Eco2.User" user "User.Eco2")
		(25 "Edge.Cuts" user "Board Geometry/Outline")
		(27 "Margin" user)
		(31 "F.CrtYd" user "Package Geometry/Place Bound Top")
		(29 "B.CrtYd" user "Package Geometry/Place Bound Bottom")
		(35 "F.Fab" user "Ref Des/Assembly Top")
		(33 "B.Fab" user "Ref Des/Assembly Bottom")
	)
	(footprint ""
		(layer "F.Cu")
		(at 70.485 -227.965 180)
		(property "Reference" "R2114"
			(at 0 0 180)
			(layer "F.SilkS")
			(hide yes)
			(effects
				(font
					(size 1.27 1.27)
				)
			)
		)
		(property "Value" "0R2J-2-GP"
			(at 0.064008 -3.993896 180)
			(unlocked yes)
			(layer "F.Fab")
			(hide yes)
			(effects
				(font
					(size 1.016 1.016)
					(thickness 0.1524)
				)
			)
		)
		(property "Device Type" "R402H16"
			(at 0.064008 -5.517896 180)
			(unlocked yes)
			(layer "F.Fab")
			(hide yes)
			(effects
				(font
					(size 1.016 1.016)
					(thickness 0.1524)
				)
			)
		)
		(duplicate_pad_numbers_are_jumpers no)
		(fp_line
			(start 0.508 -0.9398)
			(end -0.508 -0.9398)
			(stroke
				(width 0.1524)
				(type default)
			)
			(layer "F.SilkS")
		)
		(fp_line
			(start -0.508 -0.9398)
			(end -0.508 0.9398)
			(stroke
				(width 0.1524)
				(type default)
			)
			(layer "F.SilkS")
		)
		(fp_rect
			(start -0.508 0.9398)
			(end 0.508 -0.9398)
			(stroke
				(width 0)
				(type default)
			)
			(fill no)
			(layer "F.CrtYd")
		)
		(fp_rect
			(start -0.508 0.9398)
			(end 0.508 -0.9398)
			(stroke
				(width 0)
				(type default)
			)
			(fill no)
			(layer "F.Fab")
		)
		(pad "1" smd custom
			(at 0 -0.4445 180)
			(size 0.1397 0.1397)
			(layers "F.Cu" "F.Mask" "F.Paste")
			(net "MB0_CM_GATE")
			(options
				(clearance outline)
				(anchor circle)
			)
			(primitives
				(gr_poly
					(pts
						(arc
							(start -0.1778 -0.2794)
							(mid -0.249642 -0.249642)
							(end -0.2794 -0.1778)
						)
						(arc
							(start -0.2794 0.1778)
							(mid -0.249642 0.249642)
							(end -0.1778 0.2794)
						)
						(arc
							(start 0.1778 0.2794)
							(mid 0.249642 0.249642)
							(end 0.2794 0.1778)
						)
						(arc
							(start 0.2794 -0.1778)
							(mid 0.249642 -0.249642)
							(end 0.1778 -0.2794)
						)
					)
					(width 0)
					(fill yes)
				)
			)
		)
		(pad "2" smd custom
			(at 0 0.4445 180)
			(size 0.1397 0.1397)
			(layers "F.Cu" "F.Mask" "F.Paste")
			(net "MB0_CM_GATE_R")
			(options
				(clearance outline)
				(anchor circle)
			)
			(primitives
				(gr_poly
					(pts
						(arc
							(start -0.1778 -0.2794)
							(mid -0.249642 -0.249642)
							(end -0.2794 -0.1778)
						)
						(arc
							(start -0.2794 0.1778)
							(mid -0.249642 0.249642)
							(end -0.1778 0.2794)
						)
						(arc
							(start 0.1778 0.2794)
							(mid 0.249642 0.249642)
							(end 0.2794 0.1778)
						)
						(arc
							(start 0.2794 -0.1778)
							(mid 0.249642 -0.249642)
							(end 0.1778 -0.2794)
						)
					)
					(width 0)
					(fill yes)
				)
			)
		)
	)
	(footprint ""
		(layer "F.Cu")
		(at 108.59897 -74.549 180)
		(property "Reference" "R591"
			(at 0 0 180)
			(layer "F.SilkS")
			(hide yes)
			(effects
				(font
					(size 1.27 1.27)
				)
			)
		)
		(property "Value" "4K7R2F-GP"
			(at 0.064008 -3.993896 180)
			(unlocked yes)
			(layer "F.Fab")
			(hide yes)
			(effects
				(font
					(size 1.016 1.016)
					(thickness 0.1524)
				)
			)
		)
		(property "Device Type" "R402H16"
			(at 0.064008 -5.517896 180)
			(unlocked yes)
			(layer "F.Fab")
			(hide yes)
			(effects
				(font
					(size 1.016 1.016)
					(thickness 0.1524)
				)
			)
		)
		(duplicate_pad_numbers_are_jumpers no)
		(fp_line
			(start 0.508 -0.9398)
			(end -0.508 -0.9398)
			(stroke
				(width 0.1524)
				(type default)
			)
			(layer "F.SilkS")
		)
		(fp_line
			(start -0.508 -0.9398)
			(end -0.508 0.9398)
			(stroke
				(width 0.1524)
				(type default)
			)
			(layer "F.SilkS")
		)
		(fp_rect
			(start -0.508 0.9398)
			(end 0.508 -0.9398)
			(stroke
				(width 0)
				(type default)
			)
			(fill no)
			(layer "F.CrtYd")
		)
		(fp_rect
			(start -0.508 0.9398)
			(end 0.508 -0.9398)
			(stroke
				(width 0)
				(type default)
			)
			(fill no)
			(layer "F.Fab")
		)
		(pad "1" smd custom
			(at 0 -0.4445 180)
			(size 0.1397 0.1397)
			(layers "F.Cu" "F.Mask" "F.Paste")
			(net "TEMP_4_A2")
			(options
				(clearance outline)
				(anchor circle)
			)
			(primitives
				(gr_poly
					(pts
						(arc
							(start -0.1778 -0.2794)
							(mid -0.249642 -0.249642)
							(end -0.2794 -0.1778)
						)
						(arc
							(start -0.2794 0.1778)
							(mid -0.249642 0.249642)
							(end -0.1778 0.2794)
						)
						(arc
							(start 0.1778 0.2794)
							(mid 0.249642 0.249642)
							(end 0.2794 0.1778)
						)
						(arc
							(start 0.2794 -0.1778)
							(mid 0.249642 -0.249642)
							(end 0.1778 -0.2794)
						)
					)
					(width 0)
					(fill yes)
				)
			)
		)
		(pad "2" smd custom
			(at 0 0.4445 180)
			(size 0.1397 0.1397)
			(layers "F.Cu" "F.Mask" "F.Paste")
			(net "GND")
			(options
				(clearance outline)
				(anchor circle)
			)
			(primitives
				(gr_poly
					(pts
						(arc
							(start -0.1778 -0.2794)
							(mid -0.249642 -0.249642)
							(end -0.2794 -0.1778)
						)
						(arc
							(start -0.2794 0.1778)
							(mid -0.249642 0.249642)
							(end -0.1778 0.2794)
						)
						(arc
							(start 0.1778 0.2794)
							(mid 0.249642 0.249642)
							(end 0.2794 0.1778)
						)
						(arc
							(start 0.2794 -0.1778)
							(mid 0.249642 -0.249642)
							(end 0.1778 -0.2794)
						)
					)
					(width 0)
					(fill yes)
				)
			)
		)
	)
	(footprint ""
		(layer "F.Cu")
		(at 103.105966 -61.4426 90)
		(property "Reference" "SC917"
			(at 0 0 90)
			(layer "F.SilkS")
			(hide yes)
			(effects
				(font
					(size 1.27 1.27)
				)
			)
		)
		(property "Value" "SC1U6D3V1MX-GP"
			(at 1.9177 2.0193 90)
			(unlocked yes)
			(layer "F.Fab")
			(hide yes)
			(effects
				(font
					(size 1.016 1.016)
					(thickness 0.1524)
				)
			)
		)
		(property "Device Type" "C0201H14"
			(at 1.9177 0.4953 90)
			(unlocked yes)
			(layer "F.Fab")
			(hide yes)
			(effects
				(font
					(size 1.016 1.016)
					(thickness 0.1524)
				)
			)
		)
		(duplicate_pad_numbers_are_jumpers no)
		(fp_rect
			(start -0.1524 0.3048)
			(end 0.1524 -0.3048)
			(stroke
				(width 0)
				(type default)
			)
			(fill no)
			(layer "F.CrtYd")
		)
		(fp_poly
			(pts
				(xy -0.2794 0.6477) (xy -0.2794 -0.6477) (xy 0.2794 -0.6477) (xy 0.2794 -0.1905) (xy 0.1524 -0.1905)
				(xy 0.1524 -0.3048) (xy -0.1524 -0.3048) (xy -0.1524 0.3048) (xy 0.1524 0.3048) (xy 0.1524 -0.1778)
				(xy 0.2794 -0.1778) (xy 0.2794 0.6477)
			)
			(stroke
				(width 0)
				(type default)
			)
			(fill no)
			(layer "F.CrtYd")
		)
		(fp_rect
			(start -0.2794 0.6477)
			(end 0.2794 -0.6477)
			(stroke
				(width 0)
				(type default)
			)
			(fill no)
			(layer "F.Fab")
		)
		(pad "1" smd custom
			(at 0 -0.2794 90)
			(size 0.0762 0.0762)
			(layers "F.Cu" "F.Mask" "F.Paste")
			(net "HM40ADC_VDDA")
			(options
				(clearance outline)
				(anchor circle)
			)
			(primitives
				(gr_poly
					(pts
						(arc
							(start 0.1524 -0.127)
							(mid 0.137521 -0.162921)
							(end 0.1016 -0.1778)
						)
						(arc
							(start -0.1016 -0.1778)
							(mid -0.137521 -0.162921)
							(end -0.1524 -0.127)
						)
						(arc
							(start -0.1524 0.127)
							(mid -0.137521 0.162921)
							(end -0.1016 0.1778)
						)
						(arc
							(start 0.1016 0.1778)
							(mid 0.137521 0.162921)
							(end 0.1524 0.127)
						)
					)
					(width 0)
					(fill yes)
				)
			)
		)
		(pad "2" smd custom
			(at 0 0.2794 90)
			(size 0.0762 0.0762)
			(layers "F.Cu" "F.Mask" "F.Paste")
			(net "GND")
			(options
				(clearance outline)
				(anchor circle)
			)
			(primitives
				(gr_poly
					(pts
						(arc
							(start 0.1524 -0.127)
							(mid 0.137521 -0.162921)
							(end 0.1016 -0.1778)
						)
						(arc
							(start -0.1016 -0.1778)
							(mid -0.137521 -0.162921)
							(end -0.1524 -0.127)
						)
						(arc
							(start -0.1524 0.127)
							(mid -0.137521 0.162921)
							(end -0.1016 0.1778)
						)
						(arc
							(start 0.1016 0.1778)
							(mid 0.137521 0.162921)
							(end 0.1524 0.127)
						)
					)
					(width 0)
					(fill yes)
				)
			)
		)
	)
	(footprint ""
		(layer "F.Cu")
		(at 77.343 -33.401)
		(property "Reference" "SC956"
			(at 0 0 0)
			(layer "F.SilkS")
			(hide yes)
			(effects
				(font
					(size 1.27 1.27)
				)
			)
		)
		(property "Value" "SC100U6D3V0MX-2GP"
			(at -0.00254 -4.78536 0)
			(unlocked yes)
			(layer "F.Fab")
			(hide yes)
			(effects
				(font
					(size 1.016 1.016)
					(thickness 0.1524)
				)
			)
		)
		(property "Device Type" "C1210H107"
			(at -0.00254 -6.38048 0)
			(unlocked yes)
			(layer "F.Fab")
			(hide yes)
			(effects
				(font
					(size 1.016 1.016)
					(thickness 0.1524)
				)
			)
		)
		(duplicate_pad_numbers_are_jumpers no)
		(fp_line
			(start -1.5748 -2.3368)
			(end -1.5748 -0.762)
			(stroke
				(width 0.1524)
				(type default)
			)
			(layer "F.SilkS")
		)
		(fp_line
			(start -1.5748 0.762)
			(end -1.5748 2.3368)
			(stroke
				(width 0.1524)
				(type default)
			)
			(layer "F.SilkS")
		)
		(fp_line
			(start -1.5748 2.3368)
			(end 1.5748 2.3368)
			(stroke
				(width 0.1524)
				(type default)
			)
			(layer "F.SilkS")
		)
		(fp_line
			(start 1.5748 -2.3368)
			(end -1.5748 -2.3368)
			(stroke
				(width 0.1524)
				(type default)
			)
			(layer "F.SilkS")
		)
		(fp_line
			(start 1.5748 -0.762)
			(end 1.5748 -2.3368)
			(stroke
				(width 0.1524)
				(type default)
			)
			(layer "F.SilkS")
		)
		(fp_line
			(start 1.5748 2.3368)
			(end 1.5748 0.762)
			(stroke
				(width 0.1524)
				(type default)
			)
			(layer "F.SilkS")
		)
		(fp_rect
			(start -1.651 2.413)
			(end 1.651 -2.413)
			(stroke
				(width 0)
				(type default)
			)
			(fill no)
			(layer "F.CrtYd")
		)
		(fp_poly
			(pts
				(xy 1.651 2.413) (xy 1.651 -2.413) (xy -1.651 -2.413) (xy -1.651 2.413)
			)
			(stroke
				(width 0)
				(type default)
			)
			(fill no)
			(layer "F.Fab")
		)
		(pad "1" smd rect
			(at 0 -1.4732)
			(size 2.794 1.397)
			(layers "F.Cu" "F.Mask" "F.Paste")
			(net "GND")
		)
		(pad "2" smd rect
			(at 0 1.4732)
			(size 2.794 1.397)
			(layers "F.Cu" "F.Mask" "F.Paste")
			(net "SAS0_AVDD")
		)
	)
	(footprint ""
		(layer "F.Cu")
		(at 202.692 -185.42 180)
		(property "Reference" "R478"
			(at 0 0 180)
			(layer "F.SilkS")
			(hide yes)
			(effects
				(font
					(size 1.27 1.27)
				)
			)
		)
		(property "Value" "2MR2F-GP"
			(at 0.064008 -3.993896 180)
			(unlocked yes)
			(layer "F.Fab")
			(hide yes)
			(effects
				(font
					(size 1.016 1.016)
					(thickness 0.1524)
				)
			)
		)
		(property "Device Type" "R402H16"
			(at 0.064008 -5.517896 180)
			(unlocked yes)
			(layer "F.Fab")
			(hide yes)
			(effects
				(font
					(size 1.016 1.016)
					(thickness 0.1524)
				)
			)
		)
		(duplicate_pad_numbers_are_jumpers no)
		(fp_line
			(start 0.508 -0.9398)
			(end -0.508 -0.9398)
			(stroke
				(width 0.1524)
				(type default)
			)
			(layer "F.SilkS")
		)
		(fp_line
			(start -0.508 -0.9398)
			(end -0.508 0.9398)
			(stroke
				(width 0.1524)
				(type default)
			)
			(layer "F.SilkS")
		)
		(fp_rect
			(start -0.508 0.9398)
			(end 0.508 -0.9398)
			(stroke
				(width 0)
				(type default)
			)
			(fill no)
			(layer "F.CrtYd")
		)
		(fp_rect
			(start -0.508 0.9398)
			(end 0.508 -0.9398)
			(stroke
				(width 0)
				(type default)
			)
			(fill no)
			(layer "F.Fab")
		)
		(pad "1" smd custom
			(at 0 -0.4445 180)
			(size 0.1397 0.1397)
			(layers "F.Cu" "F.Mask" "F.Paste")
			(net "HB_OUT_BMC")
			(options
				(clearance outline)
				(anchor circle)
			)
			(primitives
				(gr_poly
					(pts
						(arc
							(start -0.1778 -0.2794)
							(mid -0.249642 -0.249642)
							(end -0.2794 -0.1778)
						)
						(arc
							(start -0.2794 0.1778)
							(mid -0.249642 0.249642)
							(end -0.1778 0.2794)
						)
						(arc
							(start 0.1778 0.2794)
							(mid 0.249642 0.249642)
							(end 0.2794 0.1778)
						)
						(arc
							(start 0.2794 -0.1778)
							(mid 0.249642 -0.249642)
							(end 0.1778 -0.2794)
						)
					)
					(width 0)
					(fill yes)
				)
			)
		)
		(pad "2" smd custom
			(at 0 0.4445 180)
			(size 0.1397 0.1397)
			(layers "F.Cu" "F.Mask" "F.Paste")
			(net "HB_A_IN")
			(options
				(clearance outline)
				(anchor circle)
			)
			(primitives
				(gr_poly
					(pts
						(arc
							(start -0.1778 -0.2794)
							(mid -0.249642 -0.249642)
							(end -0.2794 -0.1778)
						)
						(arc
							(start -0.2794 0.1778)
							(mid -0.249642 0.249642)
							(end -0.1778 0.2794)
						)
						(arc
							(start 0.1778 0.2794)
							(mid 0.249642 0.249642)
							(end 0.2794 0.1778)
						)
						(arc
							(start 0.2794 -0.1778)
							(mid 0.249642 -0.249642)
							(end 0.1778 -0.2794)
						)
					)
					(width 0)
					(fill yes)
				)
			)
		)
	)
	(footprint ""
		(layer "F.Cu")
		(at 318.008 -179.705 -90)
		(property "Reference" "R319"
			(at 0 0 270)
			(layer "F.SilkS")
			(hide yes)
			(effects
				(font
					(size 1.27 1.27)
				)
			)
		)
		(property "Value" "0R2J-2-GP"
			(at 0.064008 -3.993896 270)
			(unlocked yes)
			(layer "F.Fab")
			(hide yes)
			(effects
				(font
					(size 1.016 1.016)
					(thickness 0.1524)
				)
			)
		)
		(property "Device Type" "R402H16"
			(at 0.064008 -5.517896 270)
			(unlocked yes)
			(layer "F.Fab")
			(hide yes)
			(effects
				(font
					(size 1.016 1.016)
					(thickness 0.1524)
				)
			)
		)
		(duplicate_pad_numbers_are_jumpers no)
		(fp_line
			(start -0.508 -0.9398)
			(end -0.508 0.9398)
			(stroke
				(width 0.1524)
				(type default)
			)
			(layer "F.SilkS")
		)
		(fp_line
			(start 0.508 -0.9398)
			(end -0.508 -0.9398)
			(stroke
				(width 0.1524)
				(type default)
			)
			(layer "F.SilkS")
		)
		(fp_rect
			(start -0.508 0.9398)
			(end 0.508 -0.9398)
			(stroke
				(width 0)
				(type default)
			)
			(fill no)
			(layer "F.CrtYd")
		)
		(fp_rect
			(start -0.508 0.9398)
			(end 0.508 -0.9398)
			(stroke
				(width 0)
				(type default)
			)
			(fill no)
			(layer "F.Fab")
		)
		(pad "1" smd custom
			(at 0 -0.4445 270)
			(size 0.1397 0.1397)
			(layers "F.Cu" "F.Mask" "F.Paste")
			(net "ADC_P1V8_STBY")
			(options
				(clearance outline)
				(anchor circle)
			)
			(primitives
				(gr_poly
					(pts
						(arc
							(start -0.1778 -0.2794)
							(mid -0.249642 -0.249642)
							(end -0.2794 -0.1778)
						)
						(arc
							(start -0.2794 0.1778)
							(mid -0.249642 0.249642)
							(end -0.1778 0.2794)
						)
						(arc
							(start 0.1778 0.2794)
							(mid 0.249642 0.249642)
							(end 0.2794 0.1778)
						)
						(arc
							(start 0.2794 -0.1778)
							(mid 0.249642 -0.249642)
							(end 0.1778 -0.2794)
						)
					)
					(width 0)
					(fill yes)
				)
			)
		)
		(pad "2" smd custom
			(at 0 0.4445 270)
			(size 0.1397 0.1397)
			(layers "F.Cu" "F.Mask" "F.Paste")
			(net "ADC_P1V8_STBY_BMC")
			(options
				(clearance outline)
				(anchor circle)
			)
			(primitives
				(gr_poly
					(pts
						(arc
							(start -0.1778 -0.2794)
							(mid -0.249642 -0.249642)
							(end -0.2794 -0.1778)
						)
						(arc
							(start -0.2794 0.1778)
							(mid -0.249642 0.249642)
							(end -0.1778 0.2794)
						)
						(arc
							(start 0.1778 0.2794)
							(mid 0.249642 0.249642)
							(end 0.2794 0.1778)
						)
						(arc
							(start 0.2794 -0.1778)
							(mid 0.249642 -0.249642)
							(end 0.1778 -0.2794)
						)
					)
					(width 0)
					(fill yes)
				)
			)
		)
	)
	(footprint ""
		(layer "F.Cu")
		(at 96.52 -233.807)
		(property "Reference" "R661"
			(at 0 0 0)
			(layer "F.SilkS")
			(hide yes)
			(effects
				(font
					(size 1.27 1.27)
				)
			)
		)
		(property "Value" "0R2J-2-GP"
			(at 0.064008 -3.993896 0)
			(unlocked yes)
			(layer "F.Fab")
			(hide yes)
			(effects
				(font
					(size 1.016 1.016)
					(thickness 0.1524)
				)
			)
		)
		(property "Device Type" "R402H16"
			(at 0.064008 -5.517896 0)
			(unlocked yes)
			(layer "F.Fab")
			(hide yes)
			(effects
				(font
					(size 1.016 1.016)
					(thickness 0.1524)
				)
			)
		)
		(duplicate_pad_numbers_are_jumpers no)
		(fp_line
			(start -0.508 -0.9398)
			(end -0.508 0.9398)
			(stroke
				(width 0.1524)
				(type default)
			)
			(layer "F.SilkS")
		)
		(fp_line
			(start 0.508 -0.9398)
			(end -0.508 -0.9398)
			(stroke
				(width 0.1524)
				(type default)
			)
			(layer "F.SilkS")
		)
		(fp_rect
			(start -0.508 0.9398)
			(end 0.508 -0.9398)
			(stroke
				(width 0)
				(type default)
			)
			(fill no)
			(layer "F.CrtYd")
		)
		(fp_rect
			(start -0.508 0.9398)
			(end 0.508 -0.9398)
			(stroke
				(width 0)
				(type default)
			)
			(fill no)
			(layer "F.Fab")
		)
		(pad "1" smd custom
			(at 0 -0.4445)
			(size 0.1397 0.1397)
			(layers "F.Cu" "F.Mask" "F.Paste")
			(net "SAS_FAULT_LED9")
			(options
				(clearance outline)
				(anchor circle)
			)
			(primitives
				(gr_poly
					(pts
						(arc
							(start -0.1778 -0.2794)
							(mid -0.249642 -0.249642)
							(end -0.2794 -0.1778)
						)
						(arc
							(start -0.2794 0.1778)
							(mid -0.249642 0.249642)
							(end -0.1778 0.2794)
						)
						(arc
							(start 0.1778 0.2794)
							(mid 0.249642 0.249642)
							(end 0.2794 0.1778)
						)
						(arc
							(start 0.2794 -0.1778)
							(mid 0.249642 -0.249642)
							(end 0.1778 -0.2794)
						)
					)
					(width 0)
					(fill yes)
				)
			)
		)
		(pad "2" smd custom
			(at 0 0.4445)
			(size 0.1397 0.1397)
			(layers "F.Cu" "F.Mask" "F.Paste")
			(net "SAS_HDD_LED_9")
			(options
				(clearance outline)
				(anchor circle)
			)
			(primitives
				(gr_poly
					(pts
						(arc
							(start -0.1778 -0.2794)
							(mid -0.249642 -0.249642)
							(end -0.2794 -0.1778)
						)
						(arc
							(start -0.2794 0.1778)
							(mid -0.249642 0.249642)
							(end -0.1778 0.2794)
						)
						(arc
							(start 0.1778 0.2794)
							(mid 0.249642 0.249642)
							(end 0.2794 0.1778)
						)
						(arc
							(start 0.2794 -0.1778)
							(mid 0.249642 -0.249642)
							(end 0.1778 -0.2794)
						)
					)
					(width 0)
					(fill yes)
				)
			)
		)
	)
)
